(kicad_pcb
	(version 20241229)
	(generator "pcbnew")
	(generator_version "9.0")
	(general
		(thickness 1.63)
		(legacy_teardrops no)
	)
	(paper "A4")
	(title_block
		(title "CM4 Baseboard")
		(date "2026-01-05")
		(rev "1.1.1")
		(company "Antmicro Ltd")
		(comment 1 "www.antmicro.com")
		(comment 9 "footprints 334-338 of 506")
	)
	(layers
		(0 "F.Cu" signal)
		(4 "In1.Cu" power)
		(6 "In2.Cu" power)
		(8 "In3.Cu" signal)
		(10 "In4.Cu" signal)
		(2 "B.Cu" signal)
		(9 "F.Adhes" user "F.Adhesive")
		(11 "B.Adhes" user "B.Adhesive")
		(13 "F.Paste" user)
		(15 "B.Paste" user)
		(5 "F.SilkS" user "F.Silkscreen")
		(7 "B.SilkS" user "B.Silkscreen")
		(1 "F.Mask" user)
		(3 "B.Mask" user)
		(17 "Dwgs.User" user "User.Drawings")
		(19 "Cmts.User" user "User.Comments")
		(21 "Eco1.User" user "User.Eco1")
		(23 "Eco2.User" user "User.Eco2")
		(25 "Edge.Cuts" user)
		(27 "Margin" user)
		(31 "F.CrtYd" user "F.Courtyard")
		(29 "B.CrtYd" user "B.Courtyard")
		(35 "F.Fab" user)
		(33 "B.Fab" user)
	)
	(footprint "antmicro-footprints:L_Bourns-SRP3212A"
		(layer "B.Cu")
		(at 69.512962 164.7115 -90)
		(property "Reference" "L302"
			(at 2.435 -1.875 90)
			(layer "B.SilkS")
			(effects
				(font
					(size 0.7 0.7)
					(thickness 0.15)
				)
				(justify left bottom mirror)
			)
		)
		(property "Value" "L_1u_5.5A_Bourns-SRP3212A"
			(at 0.05 -2.8 90)
			(layer "B.Fab")
			(effects
				(font
					(size 0.7 0.7)
					(thickness 0.15)
				)
				(justify left bottom mirror)
			)
		)
		(property "Datasheet" "https://www.mouser.com/datasheet/2/54/SRP3212A-3011944.pdf"
			(at 0 0 270)
			(layer "B.Fab")
			(hide yes)
			(effects
				(font
					(size 1.27 1.27)
					(thickness 0.15)
				)
			)
		)
		(property "Manufacturer" "Bourns"
			(at 0 0 270)
			(unlocked yes)
			(layer "B.Fab")
			(hide yes)
			(effects
				(font
					(size 1 1)
					(thickness 0.15)
				)
				(justify mirror)
			)
		)
		(property "MPN" "SRP3212A-1R0M"
			(at 0 0 270)
			(unlocked yes)
			(layer "B.Fab")
			(hide yes)
			(effects
				(font
					(size 1 1)
					(thickness 0.15)
				)
				(justify mirror)
			)
		)
		(property "Size" "3.2x2.5"
			(at 0 0 270)
			(unlocked yes)
			(layer "B.Fab")
			(hide yes)
			(effects
				(font
					(size 1 1)
					(thickness 0.15)
				)
				(justify mirror)
			)
		)
		(property "Val" "1u/5.5A"
			(at 0 0 270)
			(unlocked yes)
			(layer "B.Fab")
			(hide yes)
			(effects
				(font
					(size 1 1)
					(thickness 0.15)
				)
				(justify mirror)
			)
		)
		(property "Author" "Antmicro"
			(at 0 0 270)
			(unlocked yes)
			(layer "B.Fab")
			(hide yes)
			(effects
				(font
					(size 1 1)
					(thickness 0.15)
				)
				(justify mirror)
			)
		)
		(property "License" "Apache-2.0"
			(at 0 0 270)
			(unlocked yes)
			(layer "B.Fab")
			(hide yes)
			(effects
				(font
					(size 1 1)
					(thickness 0.15)
				)
				(justify mirror)
			)
		)
		(property "ISat" "6.5 A"
			(at 0 0 270)
			(unlocked yes)
			(layer "B.Fab")
			(hide yes)
			(effects
				(font
					(size 1 1)
					(thickness 0.15)
				)
				(justify mirror)
			)
		)
		(property "IMax" "5.5 A"
			(at 0 0 270)
			(unlocked yes)
			(layer "B.Fab")
			(hide yes)
			(effects
				(font
					(size 1 1)
					(thickness 0.15)
				)
				(justify mirror)
			)
		)
		(sheetname "/Supply/")
		(sheetfile "supply.kicad_sch")
		(attr smd)
		(fp_line
			(start -0.4 1.25)
			(end 0.399 1.25)
			(stroke
				(width 0.15)
				(type solid)
			)
			(layer "B.SilkS")
		)
		(fp_line
			(start -0.4 -1.249)
			(end 0.399 -1.249)
			(stroke
				(width 0.15)
				(type solid)
			)
			(layer "B.SilkS")
		)
		(fp_rect
			(start -2.1 1.65)
			(end 2.1 -1.65)
			(stroke
				(width 0.05)
				(type solid)
			)
			(fill no)
			(layer "B.CrtYd")
		)
		(fp_rect
			(start -1.609 1.26)
			(end 1.609 -1.26)
			(stroke
				(width 0.15)
				(type solid)
			)
			(fill no)
			(layer "B.Fab")
		)
		(fp_text user "Author: Antmicro"
			(at -2.1 -6 90)
			(layer "B.Fab")
			(effects
				(font
					(size 0.7 0.7)
					(thickness 0.15)
				)
				(justify left bottom mirror)
			)
		)
		(fp_text user "${REFERENCE}"
			(at -2.1 -4.8 90)
			(layer "B.Fab")
			(effects
				(font
					(size 0.7 0.7)
					(thickness 0.15)
				)
				(justify left bottom mirror)
			)
		)
		(fp_text user "License: Apache-2.0"
			(at -2.1 -7.2 90)
			(layer "B.Fab")
			(effects
				(font
					(size 0.7 0.7)
					(thickness 0.15)
				)
				(justify left bottom mirror)
			)
		)
		(pad "1" smd roundrect
			(at -1.175 0 270)
			(size 1.35 2.8)
			(layers "B.Cu" "B.Mask" "B.Paste")
			(roundrect_rratio 0.1)
			(net 49 "/Supply/SW_3V3")
			(pintype "passive")
		)
		(pad "2" smd roundrect
			(at 1.175 0 270)
			(size 1.35 2.8)
			(layers "B.Cu" "B.Mask" "B.Paste")
			(roundrect_rratio 0.1)
			(net 89 "/Supply/OUT_3V3")
			(pintype "passive")
		)
	)
	(footprint "antmicro-footprints:L_Bourns-SRP3212A"
		(layer "B.Cu")
		(at 113.627962 134.5615 -90)
		(property "Reference" "L301"
			(at 2.125 -1.95 90)
			(layer "B.SilkS")
			(effects
				(font
					(size 0.7 0.7)
					(thickness 0.15)
				)
				(justify left bottom mirror)
			)
		)
		(property "Value" "L_1u_5.5A_Bourns-SRP3212A"
			(at 0.05 -2.8 90)
			(layer "B.Fab")
			(effects
				(font
					(size 0.7 0.7)
					(thickness 0.15)
				)
				(justify left bottom mirror)
			)
		)
		(property "Datasheet" "https://www.mouser.com/datasheet/2/54/SRP3212A-3011944.pdf"
			(at 0 0 270)
			(layer "B.Fab")
			(hide yes)
			(effects
				(font
					(size 1.27 1.27)
					(thickness 0.15)
				)
			)
		)
		(property "Manufacturer" "Bourns"
			(at 0 0 270)
			(unlocked yes)
			(layer "B.Fab")
			(hide yes)
			(effects
				(font
					(size 1 1)
					(thickness 0.15)
				)
				(justify mirror)
			)
		)
		(property "MPN" "SRP3212A-1R0M"
			(at 0 0 270)
			(unlocked yes)
			(layer "B.Fab")
			(hide yes)
			(effects
				(font
					(size 1 1)
					(thickness 0.15)
				)
				(justify mirror)
			)
		)
		(property "Size" "3.2x2.5"
			(at 0 0 270)
			(unlocked yes)
			(layer "B.Fab")
			(hide yes)
			(effects
				(font
					(size 1 1)
					(thickness 0.15)
				)
				(justify mirror)
			)
		)
		(property "Val" "1u/5.5A"
			(at 0 0 270)
			(unlocked yes)
			(layer "B.Fab")
			(hide yes)
			(effects
				(font
					(size 1 1)
					(thickness 0.15)
				)
				(justify mirror)
			)
		)
		(property "Author" "Antmicro"
			(at 0 0 270)
			(unlocked yes)
			(layer "B.Fab")
			(hide yes)
			(effects
				(font
					(size 1 1)
					(thickness 0.15)
				)
				(justify mirror)
			)
		)
		(property "License" "Apache-2.0"
			(at 0 0 270)
			(unlocked yes)
			(layer "B.Fab")
			(hide yes)
			(effects
				(font
					(size 1 1)
					(thickness 0.15)
				)
				(justify mirror)
			)
		)
		(property "ISat" "6.5 A"
			(at 0 0 270)
			(unlocked yes)
			(layer "B.Fab")
			(hide yes)
			(effects
				(font
					(size 1 1)
					(thickness 0.15)
				)
				(justify mirror)
			)
		)
		(property "IMax" "5.5 A"
			(at 0 0 270)
			(unlocked yes)
			(layer "B.Fab")
			(hide yes)
			(effects
				(font
					(size 1 1)
					(thickness 0.15)
				)
				(justify mirror)
			)
		)
		(sheetname "/Supply/")
		(sheetfile "supply.kicad_sch")
		(attr smd)
		(fp_line
			(start -0.4 1.25)
			(end 0.399 1.25)
			(stroke
				(width 0.15)
				(type solid)
			)
			(layer "B.SilkS")
		)
		(fp_line
			(start -0.4 -1.249)
			(end 0.399 -1.249)
			(stroke
				(width 0.15)
				(type solid)
			)
			(layer "B.SilkS")
		)
		(fp_rect
			(start -2.1 1.65)
			(end 2.1 -1.65)
			(stroke
				(width 0.05)
				(type solid)
			)
			(fill no)
			(layer "B.CrtYd")
		)
		(fp_rect
			(start -1.609 1.26)
			(end 1.609 -1.26)
			(stroke
				(width 0.15)
				(type solid)
			)
			(fill no)
			(layer "B.Fab")
		)
		(fp_text user "${REFERENCE}"
			(at -2.1 -4.8 90)
			(layer "B.Fab")
			(effects
				(font
					(size 0.7 0.7)
					(thickness 0.15)
				)
				(justify left bottom mirror)
			)
		)
		(fp_text user "License: Apache-2.0"
			(at -2.1 -7.2 90)
			(layer "B.Fab")
			(effects
				(font
					(size 0.7 0.7)
					(thickness 0.15)
				)
				(justify left bottom mirror)
			)
		)
		(fp_text user "Author: Antmicro"
			(at -2.1 -6 90)
			(layer "B.Fab")
			(effects
				(font
					(size 0.7 0.7)
					(thickness 0.15)
				)
				(justify left bottom mirror)
			)
		)
		(pad "1" smd roundrect
			(at -1.175 0 270)
			(size 1.35 2.8)
			(layers "B.Cu" "B.Mask" "B.Paste")
			(roundrect_rratio 0.1)
			(net 45 "/Supply/SW_M2")
			(pintype "passive")
		)
		(pad "2" smd roundrect
			(at 1.175 0 270)
			(size 1.35 2.8)
			(layers "B.Cu" "B.Mask" "B.Paste")
			(roundrect_rratio 0.1)
			(net 78 "/Supply/OUT_M2")
			(pintype "passive")
		)
	)
	(footprint "antmicro-footprints:C_0805_2012Metric"
		(layer "B.Cu")
		(at 68.142962 167.7665 180)
		(descr "Capacitor SMD 0805")
		(tags "capacitor SMD 0805")
		(property "Reference" "C314"
			(at -1.575 -1.8 0)
			(layer "B.SilkS")
			(effects
				(font
					(size 0.7 0.7)
					(thickness 0.15)
				)
				(justify left bottom mirror)
			)
		)
		(property "Value" "C_22u_25V_0805"
			(at -2.055717 -1.963152 0)
			(layer "B.Fab")
			(effects
				(font
					(size 0.7 0.7)
					(thickness 0.15)
				)
				(justify left bottom mirror)
			)
		)
		(property "Datasheet" "https://product.samsungsem.com/mlcc/CL21A226MAYNNN.do"
			(at 0 0 180)
			(layer "B.Fab")
			(hide yes)
			(effects
				(font
					(size 1.27 1.27)
					(thickness 0.15)
				)
			)
		)
		(property "Manufacturer" "Samsung Electro-Mechanics"
			(at 0 0 180)
			(unlocked yes)
			(layer "B.Fab")
			(hide yes)
			(effects
				(font
					(size 1 1)
					(thickness 0.15)
				)
				(justify mirror)
			)
		)
		(property "MPN" "CL21A226MAYNNNE"
			(at 0 0 180)
			(unlocked yes)
			(layer "B.Fab")
			(hide yes)
			(effects
				(font
					(size 1 1)
					(thickness 0.15)
				)
				(justify mirror)
			)
		)
		(property "Val" "22u"
			(at 0 0 180)
			(unlocked yes)
			(layer "B.Fab")
			(hide yes)
			(effects
				(font
					(size 1 1)
					(thickness 0.15)
				)
				(justify mirror)
			)
		)
		(property "License" "Apache-2.0"
			(at 0 0 180)
			(unlocked yes)
			(layer "B.Fab")
			(hide yes)
			(effects
				(font
					(size 1 1)
					(thickness 0.15)
				)
				(justify mirror)
			)
		)
		(property "Author" "Antmicro"
			(at 0 0 180)
			(unlocked yes)
			(layer "B.Fab")
			(hide yes)
			(effects
				(font
					(size 1 1)
					(thickness 0.15)
				)
				(justify mirror)
			)
		)
		(property "Voltage" "25V"
			(at 0 0 180)
			(unlocked yes)
			(layer "B.Fab")
			(hide yes)
			(effects
				(font
					(size 1 1)
					(thickness 0.15)
				)
				(justify mirror)
			)
		)
		(property "Dielectric" "X5R"
			(at 0 0 180)
			(unlocked yes)
			(layer "B.Fab")
			(hide yes)
			(effects
				(font
					(size 1 1)
					(thickness 0.15)
				)
				(justify mirror)
			)
		)
		(property "Public" "False"
			(at 0 0 180)
			(unlocked yes)
			(layer "B.Fab")
			(hide yes)
			(effects
				(font
					(size 1 1)
					(thickness 0.15)
				)
				(justify mirror)
			)
		)
		(sheetname "/Supply/")
		(sheetfile "supply.kicad_sch")
		(attr smd)
		(fp_line
			(start -0.3 0.7)
			(end 0.3 0.7)
			(stroke
				(width 0.15)
				(type solid)
			)
			(layer "B.SilkS")
		)
		(fp_line
			(start -0.3 -0.7)
			(end 0.3 -0.7)
			(stroke
				(width 0.15)
				(type solid)
			)
			(layer "B.SilkS")
		)
		(fp_rect
			(start 1.95 0.9)
			(end -1.95 -0.9)
			(stroke
				(width 0.05)
				(type default)
			)
			(fill no)
			(layer "B.CrtYd")
		)
		(fp_rect
			(start -0.95 0.675)
			(end 0.95 -0.675)
			(stroke
				(width 0.15)
				(type solid)
			)
			(fill no)
			(layer "B.Fab")
		)
		(fp_text user "License: Apache-2.0"
			(at -1.9 -4.947 0)
			(layer "B.Fab")
			(effects
				(font
					(size 0.7 0.7)
					(thickness 0.15)
				)
				(justify left bottom mirror)
			)
		)
		(fp_text user "${REFERENCE}"
			(at -1.9 -3.947 0)
			(layer "B.Fab")
			(effects
				(font
					(size 0.7 0.7)
					(thickness 0.15)
				)
				(justify left bottom mirror)
			)
		)
		(fp_text user "Author: Antmicro"
			(at -1.9 -5.947 0)
			(layer "B.Fab")
			(effects
				(font
					(size 0.7 0.7)
					(thickness 0.15)
				)
				(justify left bottom mirror)
			)
		)
		(pad "1" smd roundrect
			(at -1.1 0 180)
			(size 1.2 1.3)
			(layers "B.Cu" "B.Mask" "B.Paste")
			(roundrect_rratio 0.25)
			(net 89 "/Supply/OUT_3V3")
			(pintype "passive")
		)
		(pad "2" smd roundrect
			(at 1.1 0 180)
			(size 1.2 1.3)
			(layers "B.Cu" "B.Mask" "B.Paste")
			(roundrect_rratio 0.25)
			(net 3 "GND")
			(pintype "passive")
		)
	)
	(footprint "antmicro-footprints:R_0402_1005Metric"
		(layer "B.Cu")
		(at 50.992962 169.9165 180)
		(descr "Resistor SMD 0402")
		(tags "resistor SMD 0402")
		(property "Reference" "R423"
			(at -0.165 -1.29 0)
			(layer "B.SilkS")
			(effects
				(font
					(size 0.7 0.7)
					(thickness 0.15)
				)
				(justify left bottom mirror)
			)
		)
		(property "Value" "R_0R_0402"
			(at -1.011843 -1.772047 0)
			(layer "B.Fab")
			(effects
				(font
					(size 0.7 0.7)
					(thickness 0.15)
				)
				(justify left bottom mirror)
			)
		)
		(property "Datasheet" "https://industrial.panasonic.com/cdbs/www-data/pdf/RDA0000/AOA0000C301.pdf"
			(at 0 0 180)
			(layer "B.Fab")
			(hide yes)
			(effects
				(font
					(size 1.27 1.27)
					(thickness 0.15)
				)
			)
		)
		(property "Manufacturer" "Panasonic"
			(at 0 0 180)
			(unlocked yes)
			(layer "B.Fab")
			(hide yes)
			(effects
				(font
					(size 1 1)
					(thickness 0.15)
				)
				(justify mirror)
			)
		)
		(property "MPN" "ERJ2GE0R00X"
			(at 0 0 180)
			(unlocked yes)
			(layer "B.Fab")
			(hide yes)
			(effects
				(font
					(size 1 1)
					(thickness 0.15)
				)
				(justify mirror)
			)
		)
		(property "Val" "0R"
			(at 0 0 180)
			(unlocked yes)
			(layer "B.Fab")
			(hide yes)
			(effects
				(font
					(size 1 1)
					(thickness 0.15)
				)
				(justify mirror)
			)
		)
		(property "License" "Apache-2.0"
			(at 0 0 180)
			(unlocked yes)
			(layer "B.Fab")
			(hide yes)
			(effects
				(font
					(size 1 1)
					(thickness 0.15)
				)
				(justify mirror)
			)
		)
		(property "Author" "Antmicro"
			(at 0 0 180)
			(unlocked yes)
			(layer "B.Fab")
			(hide yes)
			(effects
				(font
					(size 1 1)
					(thickness 0.15)
				)
				(justify mirror)
			)
		)
		(property "Tolerance" "~"
			(at 0 0 180)
			(unlocked yes)
			(layer "B.Fab")
			(hide yes)
			(effects
				(font
					(size 1 1)
					(thickness 0.15)
				)
				(justify mirror)
			)
		)
		(property "Current" "1A"
			(at 0 0 180)
			(unlocked yes)
			(layer "B.Fab")
			(hide yes)
			(effects
				(font
					(size 1 1)
					(thickness 0.15)
				)
				(justify mirror)
			)
		)
		(sheetname "/Ethernet/")
		(sheetfile "ethernet.kicad_sch")
		(attr smd exclude_from_pos_files exclude_from_bom dnp)
		(fp_rect
			(start -0.925 0.47)
			(end 0.925 -0.47)
			(stroke
				(width 0.05)
				(type default)
			)
			(fill no)
			(layer "B.CrtYd")
		)
		(fp_rect
			(start -0.5 0.25)
			(end 0.5 -0.25)
			(stroke
				(width 0.15)
				(type solid)
			)
			(fill no)
			(layer "B.Fab")
		)
		(fp_text user "Author: Antmicro"
			(at -0.95 -4.169 0)
			(layer "B.Fab")
			(effects
				(font
					(size 0.7 0.7)
					(thickness 0.15)
				)
				(justify left bottom mirror)
			)
		)
		(fp_text user "${REFERENCE}"
			(at -0.95 -3.168 0)
			(layer "B.Fab")
			(effects
				(font
					(size 0.7 0.7)
					(thickness 0.15)
				)
				(justify left bottom mirror)
			)
		)
		(fp_text user "License: Apache-2.0"
			(at -0.95 -5.169 0)
			(layer "B.Fab")
			(effects
				(font
					(size 0.7 0.7)
					(thickness 0.15)
				)
				(justify left bottom mirror)
			)
		)
		(pad "1" smd roundrect
			(at -0.48 0 180)
			(size 0.59 0.64)
			(layers "B.Cu" "B.Mask" "B.Paste")
			(roundrect_rratio 0.25)
			(net 368 "Net-(U403-TRIM)")
			(pintype "passive")
		)
		(pad "2" smd roundrect
			(at 0.48 0 180)
			(size 0.59 0.64)
			(layers "B.Cu" "B.Mask" "B.Paste")
			(roundrect_rratio 0.25)
			(net 3 "GND")
			(pintype "passive")
		)
	)
	(footprint "antmicro-footprints:C_0402_1005Metric"
		(layer "B.Cu")
		(at 52.146694 155.399922 -90)
		(descr "Capacitor SMD 0402")
		(tags "capacitor SMD 0402")
		(property "Reference" "C307"
			(at -4.1 1.34 90)
			(layer "B.SilkS")
			(effects
				(font
					(size 0.7 0.7)
					(thickness 0.15)
				)
				(justify left bottom mirror)
			)
		)
		(property "Value" "C_100n_0402"
			(at -1.022927 -2.155213 90)
			(layer "B.Fab")
			(effects
				(font
					(size 0.7 0.7)
					(thickness 0.15)
				)
				(justify left bottom mirror)
			)
		)
		(property "Datasheet" "https://www.murata.com/products/productdetail?partno=GRM155R61H104KE14%23"
			(at 0 0 270)
			(layer "B.Fab")
			(hide yes)
			(effects
				(font
					(size 1.27 1.27)
					(thickness 0.15)
				)
			)
		)
		(property "Manufacturer" "Murata"
			(at 0 0 270)
			(unlocked yes)
			(layer "B.Fab")
			(hide yes)
			(effects
				(font
					(size 1 1)
					(thickness 0.15)
				)
				(justify mirror)
			)
		)
		(property "MPN" "GRM155R61H104KE14D"
			(at 0 0 270)
			(unlocked yes)
			(layer "B.Fab")
			(hide yes)
			(effects
				(font
					(size 1 1)
					(thickness 0.15)
				)
				(justify mirror)
			)
		)
		(property "Val" "100n"
			(at 0 0 270)
			(unlocked yes)
			(layer "B.Fab")
			(hide yes)
			(effects
				(font
					(size 1 1)
					(thickness 0.15)
				)
				(justify mirror)
			)
		)
		(property "License" "Apache-2.0"
			(at 0 0 270)
			(unlocked yes)
			(layer "B.Fab")
			(hide yes)
			(effects
				(font
					(size 1 1)
					(thickness 0.15)
				)
				(justify mirror)
			)
		)
		(property "Author" "Antmicro"
			(at 0 0 270)
			(unlocked yes)
			(layer "B.Fab")
			(hide yes)
			(effects
				(font
					(size 1 1)
					(thickness 0.15)
				)
				(justify mirror)
			)
		)
		(property "Voltage" "50V"
			(at 0 0 270)
			(unlocked yes)
			(layer "B.Fab")
			(hide yes)
			(effects
				(font
					(size 1 1)
					(thickness 0.15)
				)
				(justify mirror)
			)
		)
		(property "Dielectric" "X5R"
			(at 0 0 270)
			(unlocked yes)
			(layer "B.Fab")
			(hide yes)
			(effects
				(font
					(size 1 1)
					(thickness 0.15)
				)
				(justify mirror)
			)
		)
		(sheetname "/Supply/")
		(sheetfile "supply.kicad_sch")
		(attr smd)
		(fp_rect
			(start -0.925 0.47)
			(end 0.925 -0.47)
			(stroke
				(width 0.05)
				(type default)
			)
			(fill no)
			(layer "B.CrtYd")
		)
		(fp_line
			(start -0.494 0.25)
			(end 0.504 0.25)
			(stroke
				(width 0.15)
				(type solid)
			)
			(layer "B.Fab")
		)
		(fp_line
			(start 0.504 0.25)
			(end 0.504 -0.248)
			(stroke
				(width 0.15)
				(type solid)
			)
			(layer "B.Fab")
		)
		(fp_line
			(start -0.494 -0.248)
			(end -0.494 0.25)
			(stroke
				(width 0.15)
				(type solid)
			)
			(layer "B.Fab")
		)
		(fp_line
			(start 0.504 -0.248)
			(end -0.494 -0.248)
			(stroke
				(width 0.15)
				(type solid)
			)
			(layer "B.Fab")
		)
		(fp_text user "Author: Antmicro"
			(at -0.939 -3.399 90)
			(layer "B.Fab")
			(effects
				(font
					(size 0.7 0.7)
					(thickness 0.15)
				)
				(justify left bottom mirror)
			)
		)
		(fp_text user "License: Apache-2.0"
			(at -0.939 -5.799 90)
			(layer "B.Fab")
			(effects
				(font
					(size 0.7 0.7)
					(thickness 0.15)
				)
				(justify left bottom mirror)
			)
		)
		(fp_text user "${REFERENCE}"
			(at -0.939 -4.599 90)
			(layer "B.Fab")
			(effects
				(font
					(size 0.7 0.7)
					(thickness 0.15)
				)
				(justify left bottom mirror)
			)
		)
		(pad "1" smd roundrect
			(at -0.48 0 270)
			(size 0.59 0.64)
			(layers "B.Cu" "B.Mask" "B.Paste")
			(roundrect_rratio 0.25)
			(net 43 "VCC")
			(pintype "passive")
		)
		(pad "2" smd roundrect
			(at 0.48 0 270)
			(size 0.59 0.64)
			(layers "B.Cu" "B.Mask" "B.Paste")
			(roundrect_rratio 0.25)
			(net 3 "GND")
			(pintype "passive")
		)
	)
)
